(kicad_pcb
	(version 20260206)
	(generator "pcbnew")
	(generator_version "10.0")
	(general
		(thickness 1.6)
		(legacy_teardrops no)
	)
	(paper "A4")
	(title_block
		(title "03242023_DA0F0TMBIJ0_F0T_Motherboard_J_brd_V01_OCP.brd")
		(comment 1 "Grand Teton / footprints 3155-3155 of 6105")
	)
	(layers
		(0 "F.Cu" signal "TOP")
		(4 "In1.Cu" signal "GND")
		(6 "In2.Cu" signal "IN1")
		(8 "In3.Cu" signal "GND1")
		(10 "In4.Cu" signal "IN2")
		(12 "In5.Cu" signal "GND2")
		(14 "In6.Cu" signal "IN3")
		(16 "In7.Cu" signal "GND3")
		(18 "In8.Cu" signal "VCC")
		(20 "In9.Cu" signal "VCC1")
		(22 "In10.Cu" signal "GND4")
		(24 "In11.Cu" signal "IN4")
		(26 "In12.Cu" signal "GND5")
		(28 "In13.Cu" signal "IN5")
		(30 "In14.Cu" signal "GND6")
		(32 "In15.Cu" signal "IN6")
		(34 "In16.Cu" signal "GND7")
		(2 "B.Cu" signal "BOTTOM")
		(9 "F.Adhes" user "F.Adhesive")
		(11 "B.Adhes" user "B.Adhesive")
		(13 "F.Paste" user "Package Geometry/Pastemask Top")
		(15 "B.Paste" user "Package Geometry/Pastemask Bottom")
		(5 "F.SilkS" user "Ref Des/Silkscreen Top")
		(7 "B.SilkS" user "Ref Des/Silkscreen Bottom")
		(1 "F.Mask" user "Board Geometry/Soldermask Top")
		(3 "B.Mask" user "Board Geometry/Soldermask Bottom")
		(17 "Dwgs.User" user "User.Drawings")
		(19 "Cmts.User" user "User.Comments")
		(21 "Eco1.User" user "User.Eco1")
		(23 "Eco2.User" user "User.Eco2")
		(25 "Edge.Cuts" user "Board Geometry/Outline")
		(27 "Margin" user)
		(31 "F.CrtYd" user "Package Geometry/Place Bound Top")
		(29 "B.CrtYd" user "Package Geometry/Place Bound Bottom")
		(35 "F.Fab" user "Ref Des/Assembly Top")
		(33 "B.Fab" user "Ref Des/Assembly Bottom")
	)
	(footprint ""
		(layer "F.Cu")
		(at 121.59488 -92.674948 90)
		(property "Reference" "R237"
			(at 0 0 90)
			(layer "F.SilkS")
			(hide yes)
			(effects
				(font
					(size 1.27 1.27)
				)
			)
		)
		(property "Value" ""
			(at 0 0 90)
			(layer "F.Fab")
			(effects
				(font
					(size 1.27 1.27)
				)
			)
		)
		(duplicate_pad_numbers_are_jumpers no)
		(fp_line
			(start 0.7874 -0.4064)
			(end 0.7874 0.4064)
			(stroke
				(width 0.1524)
				(type default)
			)
			(layer "F.SilkS")
		)
		(fp_line
			(start -0.7874 -0.4064)
			(end 0.7874 -0.4064)
			(stroke
				(width 0.1524)
				(type default)
			)
			(layer "F.SilkS")
		)
		(fp_line
			(start 0.7874 0.4064)
			(end -0.7874 0.4064)
			(stroke
				(width 0.1524)
				(type default)
			)
			(layer "F.SilkS")
		)
		(fp_line
			(start -0.7874 0.4064)
			(end -0.7874 -0.4064)
			(stroke
				(width 0.1524)
				(type default)
			)
			(layer "F.SilkS")
		)
		(fp_line
			(start -0.12065 -0.305054)
			(end -0.12065 -0.2794)
			(stroke
				(width 0.1)
				(type default)
			)
			(layer "F.Fab")
		)
		(fp_line
			(start -0.67945 -0.305054)
			(end -0.12065 -0.305054)
			(stroke
				(width 0.1)
				(type default)
			)
			(layer "F.Fab")
		)
		(fp_line
			(start 0.67945 -0.3048)
			(end 0.67945 0.3048)
			(stroke
				(width 0.1)
				(type default)
			)
			(layer "F.Fab")
		)
		(fp_line
			(start 0.12065 -0.3048)
			(end 0.67945 -0.3048)
			(stroke
				(width 0.1)
				(type default)
			)
			(layer "F.Fab")
		)
		(fp_line
			(start 0.12065 -0.2794)
			(end 0.12065 -0.3048)
			(stroke
				(width 0.1)
				(type default)
			)
			(layer "F.Fab")
		)
		(fp_line
			(start -0.12065 -0.2794)
			(end 0.12065 -0.2794)
			(stroke
				(width 0.1)
				(type default)
			)
			(layer "F.Fab")
		)
		(fp_line
			(start 0.120396 0.2794)
			(end -0.12065 0.2794)
			(stroke
				(width 0.1)
				(type default)
			)
			(layer "F.Fab")
		)
		(fp_line
			(start -0.12065 0.2794)
			(end -0.12065 0.3048)
			(stroke
				(width 0.1)
				(type default)
			)
			(layer "F.Fab")
		)
		(fp_line
			(start 0.67945 0.3048)
			(end 0.120396 0.3048)
			(stroke
				(width 0.1)
				(type default)
			)
			(layer "F.Fab")
		)
		(fp_line
			(start 0.120396 0.3048)
			(end 0.120396 0.2794)
			(stroke
				(width 0.1)
				(type default)
			)
			(layer "F.Fab")
		)
		(fp_line
			(start -0.12065 0.3048)
			(end -0.67945 0.3048)
			(stroke
				(width 0.1)
				(type default)
			)
			(layer "F.Fab")
		)
		(fp_line
			(start -0.67945 0.3048)
			(end -0.67945 -0.305054)
			(stroke
				(width 0.1)
				(type default)
			)
			(layer "F.Fab")
		)
		(pad "1" smd circle
			(at -0.40005 0 90)
			(size 0 0)
			(layers "F.Cu" "F.Mask" "F.Paste")
			(net "H_CPU0_THERMTRIP_LVC1_R_N")
		)
		(pad "2" smd circle
			(at 0.40005 0 90)
			(size 0 0)
			(layers "F.Cu" "F.Mask" "F.Paste")
			(net "H_CPU0_THERMTRIP_VT_R_N")
		)
	)
)
